Units used: mil,,,,,,,
,,,,,,,
Designator,Comment,Layer,Footprint,Center-X(mil),Center-Y(mil),Rotation,Description
D2,8240136,TopLayer,SOT143-4L,553.15,2230.315,90,"TVS Diode WE-TVS-HS, VRWM=3.3V"
D1,8240136,TopLayer,SOT143-4L,551.181,1171.26,90,"TVS Diode WE-TVS-HS, VRWM=3.3V"
R27,4.7K,TopLayer,RESC1608X55X30NL15T15,2372.047,2755.905,90,"Precision Thick Film Chip Resistor, 4.7 KOhm, +/- 1%, -55 to 155 degC, 0603 (1608 Metric), RoHS, Tape and Reel ERJ-3EKF4701V"
R26,4.7K,TopLayer,RESC1608X55X30NL15T15,2431.102,2755.905,90,"Precision Thick Film Chip Resistor, 4.7 KOhm, +/- 1%, -55 to 155 degC, 0603 (1608 Metric), RoHS, Tape and Reel ERJ-3EKF4701V"
P3,AUX Sensor,TopLayer,HDR1X4,5286.221,4261.811,360,"Header, 4-Pin"
U10,MAC-SA5X,TopLayer,SA53,4753.937,1732.284,0,"MOD, MAC, MAC-SA5X, ATOMIC CLOCK"
R14,49.9R,TopLayer,RESC1608X55X25NL10T15,974.409,2509.843,270,"General Purpose Chip Resistor, 49.9 Ohm, +/- 1%, -55 to 155 degC, 0603 (1608 Metric), RoHS, Tape and Reel"
U14,BME280,TopLayer,FP-BME280-MFG,3533.465,2824.803,0,SENSOR PRESSURE HUMIDITY TEMP
U13,BMX160,TopLayer,FP-BMX160-MFG,3238.189,2824.803,0,IMU ACCEL/GYRO/MAG
U12,NC7SZ125M5,TopLayer,FP-318BQ-MFG,1090.551,966.535,360,IC BUF NON-INVERT 5.5V SOT23-5
U11,NC7SZ125M5,TopLayer,FP-318BQ-MFG,1102.362,1968.504,180,IC BUF NON-INVERT 5.5V SOT23-5
U8,NC7SZ125M5,TopLayer,FP-318BQ-MFG,1092.52,1486.22,360,IC BUF NON-INVERT 5.5V SOT23-5
U6,NC7SZ125M5,TopLayer,FP-318BQ-MFG,1102.362,2500,180,IC BUF NON-INVERT 5.5V SOT23-5
U4,DS90LV028AQMA,TopLayer,M08A_L,4744.095,2824.803,360,"Automotive LVDS Dual Differential Line Receiver, 8-pin Narrow SOIC"
U3,DS90LV027AQMA,TopLayer,M08A_N,5448.819,2829.331,360,"Automotive LVDS Dual Differential Driver, 8-pin Narrow SOIC"
R25,49.9R,TopLayer,RESC1608X55X25NL10T15,974.409,935.039,270,"General Purpose Chip Resistor, 49.9 Ohm, +/- 1%, -55 to 155 degC, 0603 (1608 Metric), RoHS, Tape and Reel"
R17,49.9R,TopLayer,RESC1608X55X25NL10T15,974.409,1988.189,270,"General Purpose Chip Resistor, 49.9 Ohm, +/- 1%, -55 to 155 degC, 0603 (1608 Metric), RoHS, Tape and Reel"
R13,49.9R,TopLayer,RESC1608X55X25NL10T15,4931.102,2814.961,270,"General Purpose Chip Resistor, 49.9 Ohm, +/- 1%, -55 to 155 degC, 0603 (1608 Metric), RoHS, Tape and Reel"
R12,110R,TopLayer,RESC1609X50X30NL10T20,4557.087,2874.016,270,
R11,4.7K,TopLayer,RESC1608X55X25LL10T15,5206.693,2775.591,360,"Chip Resistor, 4.7 KOhm, +/- 1%, 0.1 W, -55 to 155 degC, 0603 (1608 Metric), RoHS, Tape and Reel RC0603FR-074K7L"
R10,4.7K,TopLayer,RESC1608X55X25LL10T15,5206.693,2854.331,360,"Chip Resistor, 4.7 KOhm, +/- 1%, 0.1 W, -55 to 155 degC, 0603 (1608 Metric), RoHS, Tape and Reel RC0603FR-074K7L"
C33,0.1uF,TopLayer,CAPC1608X87X45ML20T05,3375.984,2724.409,90,C0603X104K5RACAUTO
C32,0.1uF,TopLayer,CAPC1608X87X45ML20T05,3220.472,2696.85,180,C0603X104K5RACAUTO
C31,0.1uF,TopLayer,CAPC1608X87X45ML20T05,3661.417,2925.197,270,C0603X104K5RACAUTO
C30,0.1uF,TopLayer,CAPC1608X87X45ML20T05,3535.433,2952.756,180,C0603X104K5RACAUTO
C29,0.1uF,TopLayer,CAPC1608X87X45ML20T05,1094.488,1614.173,180,C0603X104K5RACAUTO
C28,0.1uF,TopLayer,CAPC1608X87X45ML20T05,1090.551,1104.331,180,C0603X104K5RACAUTO
C27,0.1uF,TopLayer,CAPC1608X87X45ML20T05,1102.362,1840.551,0,C0603X104K5RACAUTO
C26,0.1uF,TopLayer,CAPC1608X87X45ML20T05,1102.362,2372.047,0,C0603X104K5RACAUTO
C24,0.1uF,TopLayer,CAPC1608X87X45ML20T05,5000,2864.173,270,C0603X104K5RACAUTO
C23,0.1uF,TopLayer,CAPC1608X87X45ML20T05,5226.378,2923.228,360,C0603X104K5RACAUTO
AN1,901-143-6RFX,TopLayer,AMPHENOL-901-143-6RFX,199.843,2481.063,180,"Coaxial connector, 50 Ohm, -65 to 165 degC, 5-Pin THD, RoHS, Bulk"
AN2,901-143-6RFX,TopLayer,AMPHENOL-901-143-6RFX,199.843,1956.063,180,"Coaxial connector, 50 Ohm, -65 to 165 degC, 5-Pin THD, RoHS, Bulk"
AN3,901-143-6RFX,TopLayer,AMPHENOL-901-143-6RFX,199.843,1431.063,180,"Coaxial connector, 50 Ohm, -65 to 165 degC, 5-Pin THD, RoHS, Bulk"
AN4,901-143-6RFX,TopLayer,AMPHENOL-901-143-6RFX,199.843,906.063,180,"Coaxial connector, 50 Ohm, -65 to 165 degC, 5-Pin THD, RoHS, Bulk"
J10,1909763-1,TopLayer,TECO-1909763-1_V,555.61,905.512,90,"Ultra Miniature Coaxial Connector Jack, 60 V, 50 Ohm, -40 to 90 degC, RoHS, Tape and Reel"
J9,1909763-1,TopLayer,TECO-1909763-1_V,555.61,1433.071,90,"Ultra Miniature Coaxial Connector Jack, 60 V, 50 Ohm, -40 to 90 degC, RoHS, Tape and Reel"
J6,1909763-1,TopLayer,TECO-1909763-1_V,555.61,2480.315,90,"Ultra Miniature Coaxial Connector Jack, 60 V, 50 Ohm, -40 to 90 degC, RoHS, Tape and Reel"
J5,1909763-1,TopLayer,TECO-1909763-1_V,555.61,1952.756,90,"Ultra Miniature Coaxial Connector Jack, 60 V, 50 Ohm, -40 to 90 degC, RoHS, Tape and Reel"
R37,10K,TopLayer,RESC1608X55X30LL15T20,2962.598,2696.85,180,"Chip Resistor, 10 KOhm, +/- 1%, 0.1 W, -55 to 155 degC, 0603 (1608 Metric), RoHS, Tape and Reel RMCF0603FT10K0"
U7,AT24MAC402-STUM-T,TopLayer,FP-5TS1-IPC_C,2982.284,2814.961,270,IC EEPROM 2K I2C 1MHZ SOT23-5
C25,0.1uF,TopLayer,CAPC1608X87X45ML20T05,2854.331,2814.961,270,C0603X104K5RACAUTO
R16,200 OHM,TopLayer,RESC1608X55X30NL15T15,641.732,4078.74,90,ERJ-3EKF2000V
R15,49.9R,TopLayer,RESC1608X55X25NL10T15,974.409,1456.693,270,"General Purpose Chip Resistor, 49.9 Ohm, +/- 1%, -55 to 155 degC, 0603 (1608 Metric), RoHS, Tape and Reel"
R5,ERJ-3EKF2612V,TopLayer,RESC1608X50N,6122.842,2461.063,90,"RES, 26.1K, 1%, 1/10W, TF, 0603"
U9,RCB-F9T,TopLayer,GNSS,2550.295,3503.937,360,"MOD, GPS"
U5,HTST-105-01-L-DV-A,TopLayer,SAMTEC_HTST-105-01-L-DV-A,1816.102,4086.102,360,"CONN, HDR, 2X5, VERT, 0.1IN  SHROUDED, SMT, HTSH SERIES"
U2,MP1482DS-LF,TopLayer,SOIC127P600X175-8N,6254.842,2316.063,180,"IC, DC/DC, MP1482DS, >4.75VIN, 0.923-15V OUT, SOIC8"
U1,MP1482DS-LF,TopLayer,SOIC127P600X175-8N,6734.842,1956.063,360,"IC, DC/DC, MP1482DS, >4.75VIN, 0.923-15V OUT, SOIC8"
R30,200 OHM,TopLayer,RESC1608X55X30NL15T15,1248.032,4078.74,90,ERJ-3EKF2000V
R29,200 OHM,TopLayer,RESC1608X55X30NL15T15,1047.244,4078.74,90,ERJ-3EKF2000V
R28,200 OHM,TopLayer,RESC1608X55X30NL15T15,846.457,4078.74,90,ERJ-3EKF2000V
R24,ERJ-2GE0R00X,TopLayer,RESC1005X04N,3055.118,590.551,270,"RES, 0. OHM, 1%, 1/16W, TF, AEC-Q200, 0402"
R23,ERJ-2GE0R00X,TopLayer,RESC1005X04N,2503.937,590.551,270,"RES, 0. OHM, 1%, 1/16W, TF, AEC-Q200, 0402"
R22,ERJ-3EKF4701V,TopLayer,RESC1608X50N,1419.685,1515.748,180,"RES, 4.7K, 1%, 1/10W, TF, 0603"
R21,CRCW080533R0FKEA,TopLayer,RESC2012X50N,2017.716,3750,90,"RES, 33 OHM, 1%, 1/8W, TF, 0805"
R20,CRCW080533R0FKEA,TopLayer,RESC2012X50N,1811.024,3750,90,"RES, 33 OHM, 1%, 1/8W, TF, 0805"
R19,CRCW080533R0FKEA,TopLayer,RESC2012X50N,1712.598,3750,90,"RES, 33 OHM, 1%, 1/8W, TF, 0805"
R18,CRCW080533R0FKEA,TopLayer,RESC2012X50N,1614.173,3750,90,"RES, 33 OHM, 1%, 1/8W, TF, 0805"
R9,ERJ-3EKF2201V,TopLayer,RESC1608X50N,6003.937,2362.205,270,"RES, 2.2K, 1%, 1/10W, TF, 0603"
R8,ERJ-3EKF2201V,TopLayer,RESC1608X50N,7000,1905.512,90,"RES, 2.2K, 1%, 1/10W, TF, 0603"
R7,ERJ-3EKF1002V,TopLayer,RESC1608X50N,6338.583,2460.63,180,"RES, 10K, 1%, 1/10W, TF, 0603"
R6,ERJ-3EKF1002V,TopLayer,RESC1608X50N,6763.779,1818.898,360,"RES, 10K, 1%, 1/10W, TF, 0603"
R4,ERJ-3EKF4702V,TopLayer,RESC1608X50N,6869.842,1816.063,360,"RES, 47K, 1%, 1/10W, TF, 0603"
R3,ERJ-3EKF4702V,TopLayer,RESC1608X50N,6234.842,2156.063,270,"RES, 47K, 1%, 1/10W, TF, 0603"
R2,ERJ-3EKF4702V,TopLayer,RESC1608X50N,6749.842,2116.063,90,"RES, 47K, 1%, 1/10W, TF, 0603"
R1,ERJ-3EKF2000V,TopLayer,RESC1608X50N,6129.921,2834.646,90,"RES, 200 OHM, 1%, 1/10W, TF, 0603"
P2,PCIex4,TopLayer,PCIE_4LANE_EDGE,2446.85,147.545,360,"PCIE x4 Edge Connector,OrCAD Symbol,NC"
P1,FPGA_CONN,TopLayer,FPGA_CONN,2633.9,1698.425,360,
L2,PM124SH-100M-RC,TopLayer,IND_PM124SH,6679.842,2611.063,270,"IND, PWR, 10.uH, 20%, 4A, 0.04DCR, 12.5X12.5MM, SHLD"
L1,PM124SH-100M-RC,TopLayer,IND_PM124SH,6319.842,1651.063,90,"IND, PWR, 10.uH, 20%, 4A, 0.04DCR, 12.5X12.5MM, SHLD"
F1,FUSE_0603_2.00A,TopLayer,FUSM1608X60N,1944.882,645.275,270,FUSE SLOW 2.00A 32V M 0603
D14,RED,TopLayer,DIOM1608X06N,1249.842,4226.063,90,"LED, RED, SML-LX0603, 635NM, 2V, 20MA, 0603"
D13,RED,TopLayer,DIOM1608X06N,1048.176,4226.063,90,"LED, RED, SML-LX0603, 635NM, 2V, 20MA, 0603"
D12,RED,TopLayer,DIOM1608X06N,846.509,4226.063,90,"LED, RED, SML-LX0603, 635NM, 2V, 20MA, 0603"
D11,RED,TopLayer,DIOM1608X06N,644.842,4226.063,90,"LED, RED, SML-LX0603, 635NM, 2V, 20MA, 0603"
D8,BAT54SW,TopLayer,SOT65P210X110-3N,2091.535,3602.362,180,"DIO, SCHOTTKY, BAT54S, DUAL SERIES, 30V, 200MA, SC-70"
D7,BAT54SW,TopLayer,SOT65P210X110-3N,1914.37,3602.362,180,"DIO, SCHOTTKY, BAT54S, DUAL SERIES, 30V, 200MA, SC-70"
D6,BAT54SW,TopLayer,SOT65P210X110-3N,1732.283,3602.362,180,"DIO, SCHOTTKY, BAT54S, DUAL SERIES, 30V, 200MA, SC-70"
D5,BAT54SW,TopLayer,SOT65P210X110-3N,1555.118,3602.362,180,"DIO, SCHOTTKY, BAT54S, DUAL SERIES, 30V, 200MA, SC-70"
D4,RED,TopLayer,DIOM1608X06N,6192.913,2850.394,270,"LED, RED, SML-LX0603, 635NM, 2V, 20MA, 0603"
D3,DFLZ39-TP,TopLayer,SODFL370X135-2N,1858.268,602.362,270,"DIO, ZENER, DFLZ39, 39V, 5%, 1W, SOD123FL"
C63,0.1uF,TopLayer,CAPC1608X87X45ML20T05,3587.598,645.669,360,C0603X104K5RACAUTO
C62,CAP_0805_10UF_25V,TopLayer,CAPC2012X14N,3589.528,726.063,180,"CAP, CER, 10.UF, 25V, 10%, X5R, 0805"
C61,0.1uF,TopLayer,CAPC1608X87X45ML20T05,2706.693,3169.291,90,C0603X104K5RACAUTO
C60,CAP_0805_10UF_25V,TopLayer,CAPC2012X14N,2618.11,3179.134,270,"CAP, CER, 10.UF, 25V, 10%, X5R, 0805"
C59,0.1uF,TopLayer,CAPC1608X87X45ML20T05,2864.173,3356.299,90,C0603X104K5RACAUTO
C58,CAP_0805_10UF_25V,TopLayer,CAPC2012X14N,2952.756,3362.205,270,"CAP, CER, 10.UF, 25V, 10%, X5R, 0805"
C53,CAP_0402_0.1UF_50V,BottomLayer,CAPC1005X06N,3019.843,346.063,90,"CAP, CER, 0.1UF, 50V, 10%, X7R, AEC-Q200, 0402"
C52,CAP_0402_0.1UF_50V,BottomLayer,CAPC1005X06N,2979.843,346.063,90,"CAP, CER, 0.1UF, 50V, 10%, X7R, AEC-Q200, 0402"
C51,CAP_0402_0.1UF_50V,BottomLayer,CAPC1005X06N,2854.843,346.063,90,"CAP, CER, 0.1UF, 50V, 10%, X7R, AEC-Q200, 0402"
C50,CAP_0402_0.1UF_50V,BottomLayer,CAPC1005X06N,2819.843,346.063,90,"CAP, CER, 0.1UF, 50V, 10%, X7R, AEC-Q200, 0402"
C49,CAP_0402_0.1UF_50V,BottomLayer,CAPC1005X06N,2704.843,346.063,90,"CAP, CER, 0.1UF, 50V, 10%, X7R, AEC-Q200, 0402"
C48,CAP_0402_0.1UF_50V,BottomLayer,CAPC1005X06N,2664.843,346.063,90,"CAP, CER, 0.1UF, 50V, 10%, X7R, AEC-Q200, 0402"
C47,CAP_0402_0.1UF_50V,BottomLayer,CAPC1005X06N,2511.843,346.063,90,"CAP, CER, 0.1UF, 50V, 10%, X7R, AEC-Q200, 0402"
C46,CAP_0402_0.1UF_50V,BottomLayer,CAPC1005X06N,2468.843,346.063,90,"CAP, CER, 0.1UF, 50V, 10%, X7R, AEC-Q200, 0402"
C45,CAP_0402_0.1UF_50V,BottomLayer,CAPC1005X06N,2389.843,346.063,90,"CAP, CER, 0.1UF, 50V, 10%, X7R, AEC-Q200, 0402"
C44,CAP_0402_0.1UF_50V,BottomLayer,CAPC1005X06N,2349.843,346.063,90,"CAP, CER, 0.1UF, 50V, 10%, X7R, AEC-Q200, 0402"
C22,0.033uF,TopLayer,CAPC1608X90X35NL10T15,6064.842,2361.063,90,GCM188R71H333KA55D
C21,0.1uF,TopLayer,CAPC1608X87X45ML20T05,6124.842,2171.063,360,C0603X104K5RACAUTO
C20,0.033uF,TopLayer,CAPC1608X90X35NL10T15,6939.842,1906.063,270,GCM188R71H333KA55D
C19,0.1uF,TopLayer,CAPC1608X87X45ML20T05,6874.842,2096.063,180,C0603X104K5RACAUTO
C18,0.1uF,TopLayer,CAPC1608X87X45ML20T05,6659.842,1776.063,360,C0603X104K5RACAUTO
C17,0.1uF,TopLayer,CAPC1608X87X45ML20T05,6659.842,1721.063,360,C0603X104K5RACAUTO
C16,0.1uF,TopLayer,CAPC1608X87X45ML20T05,6659.842,1671.063,360,C0603X104K5RACAUTO
C15,0.1uF,TopLayer,CAPC1608X87X45ML20T05,6659.842,1611.063,360,C0603X104K5RACAUTO
C14,CAP_0805_10UF_25V,TopLayer,CAPC2012X14N,6664.842,1531.063,180,"CAP, CER, 10.UF, 25V, 10%, X5R, 0805"
C13,CAP_0805_10UF_25V,TopLayer,CAPC2012X14N,6664.842,1421.063,180,"CAP, CER, 10.UF, 25V, 10%, X5R, 0805"
C12,0.1uF,TopLayer,CAPC1608X87X45ML20T05,6342.52,2673.228,180,C0603X104K5RACAUTO
C11,0.1uF,TopLayer,CAPC1608X87X45ML20T05,6342.52,2606.299,180,C0603X104K5RACAUTO
C10,0.1uF,TopLayer,CAPC1608X87X45ML20T05,6342.52,2535.433,180,C0603X104K5RACAUTO
C9,0.1uF,TopLayer,CAPC1608X87X45ML20T05,6342.52,2740.157,180,C0603X104K5RACAUTO
C8,CAP_0805_10UF_25V,TopLayer,CAPC2012X14N,6362.205,2858.268,90,"CAP, CER, 10.UF, 25V, 10%, X5R, 0805"
C7,CAP_0805_10UF_25V,TopLayer,CAPC2012X14N,6275.591,2858.268,90,"CAP, CER, 10.UF, 25V, 10%, X5R, 0805"
C6,CAP_0805_10UF_25V,TopLayer,CAPC2012X14N,6659.842,2131.063,90,"CAP, CER, 10.UF, 25V, 10%, X5R, 0805"
C5,CAP_0805_10UF_25V,TopLayer,CAPC2012X14N,6334.842,2146.063,270,"CAP, CER, 10.UF, 25V, 10%, X5R, 0805"
C4,CAP_0603_0.01UF_50V,TopLayer,CAPC1608X10N,6519.842,1986.063,270,"CAP, CER, 0.01UF, 50V, 10%, X7R, 0603"
C3,CAP_0603_0.01UF_50V,TopLayer,CAPC1608X10N,6469.842,2271.063,90,"CAP, CER, 0.01UF, 50V, 10%, X7R, 0603"
C2,0.1uF,TopLayer,CAPC1608X87X45ML20T05,2106.299,657.48,270,C0603X104K5RACAUTO
C1,CAP_0805_10UF_25V,TopLayer,CAPC2012X14N,2019.685,665.354,90,"CAP, CER, 10.UF, 25V, 10%, X5R, 0805"
